# BASEBOARD_FAB2 (Tioga Pass) — schematic netlist excerpt (pin names and nets, part order shuffled) for the footprints in the layout excerpt that follows; sources: Cadence DE-HDL packaged netlist, KiCad conversion of Wiwynn_Tioga_Pass_MB.brd

J6E1  SCONN120_H61426002  CONN  pkg SM  page 194
  IOA1  = PVCCMCP_CPU0
  IOA2  = PVCCMCP_CPU0
  IOA3  = PVCCMCP_CPU0
  IOA4  = VSENSE_PVCCMCP_CPU0_SKT_VSEN
  IOA5  = PVCCMCP_CPU0
  IOA6  = PVCCMCP_CPU0
  IOA7  = PVCCMCP_CPU0
  IOA8  = PVCCMCP_CPU0
  IOA9  = PVCCMCP_CPU0
  IOA10  = PVCCMCP_CPU0
  IOA11  = PVCCMCP_CPU0
  IOA12  = PVCCMCP_CPU0
  IOA13  = PVCCMCP_CPU0
  IOA14  = PVCCMCP_CPU0
  IOA15  = PVCCMCP_CPU0
  IOA16  = PVCCMCP_CPU0
  IOA17  = PVCCMCP_CPU0
  IOA18  = PVCCMCP_CPU0
  IOA19  = GND
  IOA20  = GND
  IOB1  = PVCCMCP_CPU0
  IOB2  = PVCCMCP_CPU0
  IOB3  = PVCCMCP_CPU0
  IOB4  = VSENSE_PVCCMCP_CPU0_SKT_VRTN
  IOB5  = PVCCMCP_CPU0
  IOB6  = PVCCMCP_CPU0
  IOB7  = PVCCMCP_CPU0
  IOB8  = PVCCMCP_CPU0
  IOB9  = PVCCMCP_CPU0
  IOB10  = PVCCMCP_CPU0
  IOB11  = PVCCMCP_CPU0
  IOB12  = PVCCMCP_CPU0
  IOB13  = PVCCMCP_CPU0
  IOB14  = PVCCMCP_CPU0
  IOB15  = PVCCMCP_CPU0
  IOB16  = PVCCMCP_CPU0
  IOB17  = PVCCMCP_CPU0
  IOB18  = PVCCMCP_CPU0
  IOB19  = GND
  IOB20  = GND
  IOC1  = PVCCMCP_CPU0
  IOC2  = PVCCMCP_CPU0
  IOC3  = PVCCMCP_CPU0
  IOC4  = PVCCMCP_CPU0
  IOC5  = PVCCMCP_CPU0
  IOC6  = PVCCMCP_CPU0
  IOC7  = PVCCMCP_CPU0
  IOC8  = PVCCMCP_CPU0
  IOC9  = PVCCMCP_CPU0
  IOC10  = PVCCMCP_CPU0
  IOC11  = PVCCMCP_CPU0
  IOC12  = PVCCMCP_CPU0
  IOC13  = PVCCMCP_CPU0
  IOC14  = PVCCMCP_CPU0
  IOC15  = PVCCMCP_CPU0
  IOC16  = PVCCMCP_CPU0
  IOC17  = PVCCMCP_CPU0
  IOC18  = PVCCMCP_CPU0
  IOC19  = GND
  IOC20  = GND
  IOD1  = VSENSE_P1V8MCP_CPU0_SKT_VSEN
  IOD2  = VSENSE_P1V8MCP_CPU0_SKT_VRTN
  IOD3  = P1V8_MCP_CPU0
  IOD4  = GND
  IOD5  = GND
  IOD6  = GND
  IOD7  = GND
  IOD8  = GND
  IOD9  = GND
  IOD10  = GND
  IOD11  = GND
  IOD12  = GND
  IOD13  = GND
  IOD14  = GND
  IOD15  = GND
  IOD16  = GND
  IOD17  = GND
  IOD18  = GND
  IOD19  = GND
  IOD20  = GND
  IOE1  = P1V8_MCP_CPU0
  IOE2  = P1V8_MCP_CPU0
  IOE3  = P1V8_MCP_CPU0
  IOE4  = GND
  IOE5  = CLK_322M_156M_CPU0_OSC_VRM_DP
  IOE6  = GND
  IOE7  = GND
  IOE8  = GND
  IOE9  = GND
  IOE10  = GND
  IOE11  = GND
  IOE12  = GND
  IOE13  = GND
  IOE14  = GND
  IOE15  = GND
  IOE16  = GND
  IOE17  = GND
  IOE18  = GND
  IOE19  = GND
  IOE20  = GND
  IOF1  = P1V8_MCP_CPU0
  IOF2  = P1V8_MCP_CPU0
  IOF3  = P1V8_MCP_CPU0
  IOF4  = GND
  IOF5  = CLK_322M_156M_CPU0_OSC_VRM_DN
  IOF6  = GND
  IOF7  = GND
  IOF8  = GND
  IOF9  = GND
  IOF10  = GND
  IOF11  = GND
  IOF12  = GND
  IOF13  = GND
  IOF14  = GND
  IOF15  = GND
  IOF16  = GND
  IOF17  = GND
  IOF18  = GND
  IOF19  = GND
  IOF20  = GND

(kicad_pcb
	(version 20260206)
	(generator "pcbnew")
	(generator_version "10.0")
	(general
		(thickness 1.6)
		(legacy_teardrops no)
	)
	(paper "A4")
	(title_block
		(title "Wiwynn_Tioga_Pass_MB.brd")
		(comment 1 "Tioga Pass / footprint 587 of 4770 (J6E1), pads 50-101 of 122")
	)
	(layers
		(0 "F.Cu" signal "TOP")
		(4 "In1.Cu" signal "L2GND")
		(6 "In2.Cu" signal "L3")
		(8 "In3.Cu" signal "L4GND")
		(10 "In4.Cu" signal "L5")
		(12 "In5.Cu" signal "L6GND")
		(14 "In6.Cu" signal "L7VCC")
		(16 "In7.Cu" signal "L8VCC")
		(18 "In8.Cu" signal "L9GND")
		(20 "In9.Cu" signal "L10")
		(22 "In10.Cu" signal "L11GND")
		(24 "In11.Cu" signal "L12")
		(26 "In12.Cu" signal "L13GND")
		(2 "B.Cu" signal "BOTTOM")
		(9 "F.Adhes" user "F.Adhesive")
		(11 "B.Adhes" user "B.Adhesive")
		(13 "F.Paste" user "Package Geometry/Pastemask Top")
		(15 "B.Paste" user "Package Geometry/Pastemask Bottom")
		(5 "F.SilkS" user "Ref Des/Silkscreen Top")
		(7 "B.SilkS" user "Ref Des/Silkscreen Bottom")
		(1 "F.Mask" user "Board Geometry/Soldermask Top")
		(3 "B.Mask" user "Board Geometry/Soldermask Bottom")
		(17 "Dwgs.User" user "User.Drawings")
		(19 "Cmts.User" user "User.Comments")
		(21 "Eco1.User" user "User.Eco1")
		(23 "Eco2.User" user "User.Eco2")
		(25 "Edge.Cuts" user "Board Geometry/Outline")
		(27 "Margin" user)
		(31 "F.CrtYd" user "Package Geometry/Place Bound Top")
		(29 "B.CrtYd" user "Package Geometry/Place Bound Bottom")
		(35 "F.Fab" user "Ref Des/Assembly Top")
		(33 "B.Fab" user "Ref Des/Assembly Bottom")
	)
	(footprint ""
		(layer "F.Cu")
		(at 329.594972 -43.80103 90)
		(property "Reference" "J6E1"
			(at -3.59283 -5.018024 90)
			(unlocked yes)
			(layer "F.SilkS")
			(effects
				(font
					(size 0.7874 0.5842)
					(thickness 0.1524)
				)
			)
		)
		(property "Value" ""
			(at 0 0 90)
			(layer "F.Fab")
			(effects
				(font
					(size 1.27 1.27)
				)
			)
		)
		(duplicate_pad_numbers_are_jumpers no)
		(pad "C8" smd circle
			(at -2.54 8.89 90)
			(size 0.635 0.635)
			(layers "F.Cu" "F.Mask" "F.Paste")
			(net "PVCCMCP_CPU0")
		)
		(pad "C9" smd circle
			(at -2.54 10.16 90)
			(size 0.635 0.635)
			(layers "F.Cu" "F.Mask" "F.Paste")
			(net "PVCCMCP_CPU0")
		)
		(pad "C10" smd circle
			(at -2.54 11.43 90)
			(size 0.635 0.635)
			(layers "F.Cu" "F.Mask" "F.Paste")
			(net "PVCCMCP_CPU0")
		)
		(pad "C11" smd circle
			(at -2.54 12.7 90)
			(size 0.635 0.635)
			(layers "F.Cu" "F.Mask" "F.Paste")
			(net "PVCCMCP_CPU0")
		)
		(pad "C12" smd circle
			(at -2.54 13.97 90)
			(size 0.635 0.635)
			(layers "F.Cu" "F.Mask" "F.Paste")
			(net "PVCCMCP_CPU0")
		)
		(pad "C13" smd circle
			(at -2.54 15.24 90)
			(size 0.635 0.635)
			(layers "F.Cu" "F.Mask" "F.Paste")
			(net "PVCCMCP_CPU0")
		)
		(pad "C14" smd circle
			(at -2.54 16.51 90)
			(size 0.635 0.635)
			(layers "F.Cu" "F.Mask" "F.Paste")
			(net "PVCCMCP_CPU0")
		)
		(pad "C15" smd circle
			(at -2.54 17.78 90)
			(size 0.635 0.635)
			(layers "F.Cu" "F.Mask" "F.Paste")
			(net "PVCCMCP_CPU0")
		)
		(pad "C16" smd circle
			(at -2.54 19.05 90)
			(size 0.635 0.635)
			(layers "F.Cu" "F.Mask" "F.Paste")
			(net "PVCCMCP_CPU0")
		)
		(pad "C17" smd circle
			(at -2.54 20.32 90)
			(size 0.635 0.635)
			(layers "F.Cu" "F.Mask" "F.Paste")
			(net "PVCCMCP_CPU0")
		)
		(pad "C18" smd circle
			(at -2.54 21.59 90)
			(size 0.635 0.635)
			(layers "F.Cu" "F.Mask" "F.Paste")
			(net "PVCCMCP_CPU0")
		)
		(pad "C19" smd circle
			(at -2.54 22.86 90)
			(size 0.635 0.635)
			(layers "F.Cu" "F.Mask" "F.Paste")
			(net "GND")
		)
		(pad "C20" smd circle
			(at -2.54 24.13 90)
			(size 0.635 0.635)
			(layers "F.Cu" "F.Mask" "F.Paste")
			(net "GND")
		)
		(pad "D1" smd circle
			(at -3.81 0 90)
			(size 0.635 0.635)
			(layers "F.Cu" "F.Mask" "F.Paste")
			(net "VSENSE_P1V8MCP_CPU0_SKT_VSEN")
		)
		(pad "D2" smd circle
			(at -3.81 1.27 90)
			(size 0.635 0.635)
			(layers "F.Cu" "F.Mask" "F.Paste")
			(net "VSENSE_P1V8MCP_CPU0_SKT_VRTN")
		)
		(pad "D3" smd circle
			(at -3.81 2.54 90)
			(size 0.635 0.635)
			(layers "F.Cu" "F.Mask" "F.Paste")
			(net "P1V8_MCP_CPU0")
		)
		(pad "D4" smd circle
			(at -3.81 3.81 90)
			(size 0.635 0.635)
			(layers "F.Cu" "F.Mask" "F.Paste")
			(net "GND")
		)
		(pad "D5" smd circle
			(at -3.81 5.08 90)
			(size 0.635 0.635)
			(layers "F.Cu" "F.Mask" "F.Paste")
			(net "GND")
		)
		(pad "D6" smd circle
			(at -3.81 6.35 90)
			(size 0.635 0.635)
			(layers "F.Cu" "F.Mask" "F.Paste")
			(net "GND")
		)
		(pad "D7" smd circle
			(at -3.81 7.62 90)
			(size 0.635 0.635)
			(layers "F.Cu" "F.Mask" "F.Paste")
			(net "GND")
		)
		(pad "D8" smd circle
			(at -3.81 8.89 90)
			(size 0.635 0.635)
			(layers "F.Cu" "F.Mask" "F.Paste")
			(net "GND")
		)
		(pad "D9" smd circle
			(at -3.81 10.16 90)
			(size 0.635 0.635)
			(layers "F.Cu" "F.Mask" "F.Paste")
			(net "GND")
		)
		(pad "D10" smd circle
			(at -3.81 11.43 90)
			(size 0.635 0.635)
			(layers "F.Cu" "F.Mask" "F.Paste")
			(net "GND")
		)
		(pad "D11" smd circle
			(at -3.81 12.7 90)
			(size 0.635 0.635)
			(layers "F.Cu" "F.Mask" "F.Paste")
			(net "GND")
		)
		(pad "D12" smd circle
			(at -3.81 13.97 90)
			(size 0.635 0.635)
			(layers "F.Cu" "F.Mask" "F.Paste")
			(net "GND")
		)
		(pad "D13" smd circle
			(at -3.81 15.24 90)
			(size 0.635 0.635)
			(layers "F.Cu" "F.Mask" "F.Paste")
			(net "GND")
		)
		(pad "D14" smd circle
			(at -3.81 16.51 90)
			(size 0.635 0.635)
			(layers "F.Cu" "F.Mask" "F.Paste")
			(net "GND")
		)
		(pad "D15" smd circle
			(at -3.81 17.78 90)
			(size 0.635 0.635)
			(layers "F.Cu" "F.Mask" "F.Paste")
			(net "GND")
		)
		(pad "D16" smd circle
			(at -3.81 19.05 90)
			(size 0.635 0.635)
			(layers "F.Cu" "F.Mask" "F.Paste")
			(net "GND")
		)
		(pad "D17" smd circle
			(at -3.81 20.32 90)
			(size 0.635 0.635)
			(layers "F.Cu" "F.Mask" "F.Paste")
			(net "GND")
		)
		(pad "D18" smd circle
			(at -3.81 21.59 90)
			(size 0.635 0.635)
			(layers "F.Cu" "F.Mask" "F.Paste")
			(net "GND")
		)
		(pad "D19" smd circle
			(at -3.81 22.86 90)
			(size 0.635 0.635)
			(layers "F.Cu" "F.Mask" "F.Paste")
			(net "GND")
		)
		(pad "D20" smd circle
			(at -3.81 24.13 90)
			(size 0.635 0.635)
			(layers "F.Cu" "F.Mask" "F.Paste")
			(net "GND")
		)
		(pad "E1" smd circle
			(at -5.08 0 90)
			(size 0.635 0.635)
			(layers "F.Cu" "F.Mask" "F.Paste")
			(net "P1V8_MCP_CPU0")
		)
		(pad "E2" smd circle
			(at -5.08 1.27 90)
			(size 0.635 0.635)
			(layers "F.Cu" "F.Mask" "F.Paste")
			(net "P1V8_MCP_CPU0")
		)
		(pad "E3" smd circle
			(at -5.08 2.54 90)
			(size 0.635 0.635)
			(layers "F.Cu" "F.Mask" "F.Paste")
			(net "P1V8_MCP_CPU0")
		)
		(pad "E4" smd circle
			(at -5.08 3.81 90)
			(size 0.635 0.635)
			(layers "F.Cu" "F.Mask" "F.Paste")
			(net "GND")
		)
		(pad "E5" smd circle
			(at -5.08 5.08 90)
			(size 0.635 0.635)
			(layers "F.Cu" "F.Mask" "F.Paste")
			(net "CLK_322M_156M_CPU0_OSC_VRM_DP")
		)
		(pad "E6" smd circle
			(at -5.08 6.35 90)
			(size 0.635 0.635)
			(layers "F.Cu" "F.Mask" "F.Paste")
			(net "GND")
		)
		(pad "E7" smd circle
			(at -5.08 7.62 90)
			(size 0.635 0.635)
			(layers "F.Cu" "F.Mask" "F.Paste")
			(net "GND")
		)
		(pad "E8" smd circle
			(at -5.08 8.89 90)
			(size 0.635 0.635)
			(layers "F.Cu" "F.Mask" "F.Paste")
			(net "GND")
		)
		(pad "E9" smd circle
			(at -5.08 10.16 90)
			(size 0.635 0.635)
			(layers "F.Cu" "F.Mask" "F.Paste")
			(net "GND")
		)
		(pad "E10" smd circle
			(at -5.08 11.43 90)
			(size 0.635 0.635)
			(layers "F.Cu" "F.Mask" "F.Paste")
			(net "GND")
		)
		(pad "E11" smd circle
			(at -5.08 12.7 90)
			(size 0.635 0.635)
			(layers "F.Cu" "F.Mask" "F.Paste")
			(net "GND")
		)
		(pad "E12" smd circle
			(at -5.08 13.97 90)
			(size 0.635 0.635)
			(layers "F.Cu" "F.Mask" "F.Paste")
			(net "GND")
		)
		(pad "E13" smd circle
			(at -5.08 15.24 90)
			(size 0.635 0.635)
			(layers "F.Cu" "F.Mask" "F.Paste")
			(net "GND")
		)
		(pad "E14" smd circle
			(at -5.08 16.51 90)
			(size 0.635 0.635)
			(layers "F.Cu" "F.Mask" "F.Paste")
			(net "GND")
		)
		(pad "E15" smd circle
			(at -5.08 17.78 90)
			(size 0.635 0.635)
			(layers "F.Cu" "F.Mask" "F.Paste")
			(net "GND")
		)
		(pad "E16" smd circle
			(at -5.08 19.05 90)
			(size 0.635 0.635)
			(layers "F.Cu" "F.Mask" "F.Paste")
			(net "GND")
		)
		(pad "E17" smd circle
			(at -5.08 20.32 90)
			(size 0.635 0.635)
			(layers "F.Cu" "F.Mask" "F.Paste")
			(net "GND")
		)
		(pad "E18" smd circle
			(at -5.08 21.59 90)
			(size 0.635 0.635)
			(layers "F.Cu" "F.Mask" "F.Paste")
			(net "GND")
		)
		(pad "E19" smd circle
			(at -5.08 22.86 90)
			(size 0.635 0.635)
			(layers "F.Cu" "F.Mask" "F.Paste")
			(net "GND")
		)
	)
)
